# SCM (Grand Teton) — schematic netlist excerpt (pin names and nets, part order shuffled) for the footprints in the layout excerpt that follows; sources: Cadence DE-HDL packaged netlist, KiCad conversion of 12092022_DA0F0TMDCD0_F0T_Management_Board_D_brd_V3_OCP.brd

R399  Q_RES  0 5% CHIP  pkg 0402LF  page 56 : A = EN_P1V0_AUX ; B = EN_P1V0_AUX_R
R841  Q_RES  33.2 1% CHIP  pkg 0402LF  page 35 : A = PWRGD_SYS_PWROK_PLD ; B = PWRGD_SYS_PWROK

(kicad_pcb
	(version 20260206)
	(generator "pcbnew")
	(generator_version "10.0")
	(general
		(thickness 1.6)
		(legacy_teardrops no)
	)
	(paper "A4")
	(title_block
		(title "12092022_DA0F0TMDCD0_F0T_Management_Board_D_brd_V3_OCP.brd")
		(comment 1 "Grand Teton / footprints 535-536 of 1440")
	)
	(layers
		(0 "F.Cu" signal "TOP")
		(4 "In1.Cu" signal "GND")
		(6 "In2.Cu" signal "IN1")
		(8 "In3.Cu" signal "GND1")
		(10 "In4.Cu" signal "IN2")
		(12 "In5.Cu" signal "VCC")
		(14 "In6.Cu" signal "VCC1")
		(16 "In7.Cu" signal "IN3")
		(18 "In8.Cu" signal "GND2")
		(20 "In9.Cu" signal "IN4")
		(22 "In10.Cu" signal "GND3")
		(2 "B.Cu" signal "BOTTOM")
		(9 "F.Adhes" user "F.Adhesive")
		(11 "B.Adhes" user "B.Adhesive")
		(13 "F.Paste" user "Package Geometry/Pastemask Top")
		(15 "B.Paste" user "Package Geometry/Pastemask Bottom")
		(5 "F.SilkS" user "Ref Des/Silkscreen Top")
		(7 "B.SilkS" user "Ref Des/Silkscreen Bottom")
		(1 "F.Mask" user "Board Geometry/Soldermask Top")
		(3 "B.Mask" user "Board Geometry/Soldermask Bottom")
		(17 "Dwgs.User" user "User.Drawings")
		(19 "Cmts.User" user "User.Comments")
		(21 "Eco1.User" user "User.Eco1")
		(23 "Eco2.User" user "User.Eco2")
		(25 "Edge.Cuts" user "Board Geometry/Outline")
		(27 "Margin" user)
		(31 "F.CrtYd" user "Package Geometry/Place Bound Top")
		(29 "B.CrtYd" user "Package Geometry/Place Bound Bottom")
		(35 "F.Fab" user "Ref Des/Assembly Top")
		(33 "B.Fab" user "Ref Des/Assembly Bottom")
	)
	(footprint ""
		(layer "F.Cu")
		(at 12.319 -97.536 180)
		(property "Reference" "R841"
			(at 0 0 180)
			(layer "F.SilkS")
			(hide yes)
			(effects
				(font
					(size 1.27 1.27)
				)
			)
		)
		(property "Value" ""
			(at 0 0 180)
			(layer "F.Fab")
			(effects
				(font
					(size 1.27 1.27)
				)
			)
		)
		(duplicate_pad_numbers_are_jumpers no)
		(fp_line
			(start 0.7874 0.4064)
			(end -0.7874 0.4064)
			(stroke
				(width 0.1524)
				(type default)
			)
			(layer "F.SilkS")
		)
		(fp_line
			(start 0.7874 -0.4064)
			(end 0.7874 0.4064)
			(stroke
				(width 0.1524)
				(type default)
			)
			(layer "F.SilkS")
		)
		(fp_line
			(start -0.7874 0.4064)
			(end -0.7874 -0.4064)
			(stroke
				(width 0.1524)
				(type default)
			)
			(layer "F.SilkS")
		)
		(fp_line
			(start -0.7874 -0.4064)
			(end 0.7874 -0.4064)
			(stroke
				(width 0.1524)
				(type default)
			)
			(layer "F.SilkS")
		)
		(fp_line
			(start 0.67945 0.3048)
			(end 0.120396 0.3048)
			(stroke
				(width 0.1)
				(type default)
			)
			(layer "F.Fab")
		)
		(fp_line
			(start 0.67945 -0.3048)
			(end 0.67945 0.3048)
			(stroke
				(width 0.1)
				(type default)
			)
			(layer "F.Fab")
		)
		(fp_line
			(start 0.12065 -0.2794)
			(end 0.12065 -0.3048)
			(stroke
				(width 0.1)
				(type default)
			)
			(layer "F.Fab")
		)
		(fp_line
			(start 0.12065 -0.3048)
			(end 0.67945 -0.3048)
			(stroke
				(width 0.1)
				(type default)
			)
			(layer "F.Fab")
		)
		(fp_line
			(start 0.120396 0.3048)
			(end 0.120396 0.2794)
			(stroke
				(width 0.1)
				(type default)
			)
			(layer "F.Fab")
		)
		(fp_line
			(start 0.120396 0.2794)
			(end -0.12065 0.2794)
			(stroke
				(width 0.1)
				(type default)
			)
			(layer "F.Fab")
		)
		(fp_line
			(start -0.12065 0.3048)
			(end -0.67945 0.3048)
			(stroke
				(width 0.1)
				(type default)
			)
			(layer "F.Fab")
		)
		(fp_line
			(start -0.12065 0.2794)
			(end -0.12065 0.3048)
			(stroke
				(width 0.1)
				(type default)
			)
			(layer "F.Fab")
		)
		(fp_line
			(start -0.12065 -0.2794)
			(end 0.12065 -0.2794)
			(stroke
				(width 0.1)
				(type default)
			)
			(layer "F.Fab")
		)
		(fp_line
			(start -0.12065 -0.305054)
			(end -0.12065 -0.2794)
			(stroke
				(width 0.1)
				(type default)
			)
			(layer "F.Fab")
		)
		(fp_line
			(start -0.67945 0.3048)
			(end -0.67945 -0.305054)
			(stroke
				(width 0.1)
				(type default)
			)
			(layer "F.Fab")
		)
		(fp_line
			(start -0.67945 -0.305054)
			(end -0.12065 -0.305054)
			(stroke
				(width 0.1)
				(type default)
			)
			(layer "F.Fab")
		)
		(pad "1" smd circle
			(at -0.40005 0 180)
			(size 0 0)
			(layers "F.Cu" "F.Mask" "F.Paste")
			(net "PWRGD_SYS_PWROK_PLD")
		)
		(pad "2" smd circle
			(at 0.40005 0 180)
			(size 0 0)
			(layers "F.Cu" "F.Mask" "F.Paste")
			(net "PWRGD_SYS_PWROK")
		)
	)
	(footprint ""
		(layer "F.Cu")
		(at 16.235172 -31.66237 90)
		(property "Reference" "R399"
			(at 0 0 90)
			(layer "F.SilkS")
			(hide yes)
			(effects
				(font
					(size 1.27 1.27)
				)
			)
		)
		(property "Value" ""
			(at 0 0 90)
			(layer "F.Fab")
			(effects
				(font
					(size 1.27 1.27)
				)
			)
		)
		(duplicate_pad_numbers_are_jumpers no)
		(fp_line
			(start 0.7874 -0.4064)
			(end 0.7874 0.4064)
			(stroke
				(width 0.1524)
				(type default)
			)
			(layer "F.SilkS")
		)
		(fp_line
			(start -0.7874 -0.4064)
			(end 0.7874 -0.4064)
			(stroke
				(width 0.1524)
				(type default)
			)
			(layer "F.SilkS")
		)
		(fp_line
			(start 0.7874 0.4064)
			(end -0.7874 0.4064)
			(stroke
				(width 0.1524)
				(type default)
			)
			(layer "F.SilkS")
		)
		(fp_line
			(start -0.7874 0.4064)
			(end -0.7874 -0.4064)
			(stroke
				(width 0.1524)
				(type default)
			)
			(layer "F.SilkS")
		)
		(fp_line
			(start -0.12065 -0.305054)
			(end -0.12065 -0.2794)
			(stroke
				(width 0.1)
				(type default)
			)
			(layer "F.Fab")
		)
		(fp_line
			(start -0.67945 -0.305054)
			(end -0.12065 -0.305054)
			(stroke
				(width 0.1)
				(type default)
			)
			(layer "F.Fab")
		)
		(fp_line
			(start 0.67945 -0.3048)
			(end 0.67945 0.3048)
			(stroke
				(width 0.1)
				(type default)
			)
			(layer "F.Fab")
		)
		(fp_line
			(start 0.12065 -0.3048)
			(end 0.67945 -0.3048)
			(stroke
				(width 0.1)
				(type default)
			)
			(layer "F.Fab")
		)
		(fp_line
			(start 0.12065 -0.2794)
			(end 0.12065 -0.3048)
			(stroke
				(width 0.1)
				(type default)
			)
			(layer "F.Fab")
		)
		(fp_line
			(start -0.12065 -0.2794)
			(end 0.12065 -0.2794)
			(stroke
				(width 0.1)
				(type default)
			)
			(layer "F.Fab")
		)
		(fp_line
			(start 0.120396 0.2794)
			(end -0.12065 0.2794)
			(stroke
				(width 0.1)
				(type default)
			)
			(layer "F.Fab")
		)
		(fp_line
			(start -0.12065 0.2794)
			(end -0.12065 0.3048)
			(stroke
				(width 0.1)
				(type default)
			)
			(layer "F.Fab")
		)
		(fp_line
			(start 0.67945 0.3048)
			(end 0.120396 0.3048)
			(stroke
				(width 0.1)
				(type default)
			)
			(layer "F.Fab")
		)
		(fp_line
			(start 0.120396 0.3048)
			(end 0.120396 0.2794)
			(stroke
				(width 0.1)
				(type default)
			)
			(layer "F.Fab")
		)
		(fp_line
			(start -0.12065 0.3048)
			(end -0.67945 0.3048)
			(stroke
				(width 0.1)
				(type default)
			)
			(layer "F.Fab")
		)
		(fp_line
			(start -0.67945 0.3048)
			(end -0.67945 -0.305054)
			(stroke
				(width 0.1)
				(type default)
			)
			(layer "F.Fab")
		)
		(pad "1" smd circle
			(at -0.40005 0 90)
			(size 0 0)
			(layers "F.Cu" "F.Mask" "F.Paste")
			(net "EN_P1V0_AUX")
		)
		(pad "2" smd circle
			(at 0.40005 0 90)
			(size 0 0)
			(layers "F.Cu" "F.Mask" "F.Paste")
			(net "EN_P1V0_AUX_R")
		)
	)
)
